# S9S_MB_2U (Grand Teton) — schematic netlist excerpt (pin names and nets, part order shuffled) for the footprints in the layout excerpt that follows; sources: Cadence DE-HDL packaged netlist, KiCad conversion of 03242023_DA0F0TMBIJ0_F0T_Motherboard_J_brd_V01_OCP.brd

PC2225  Q_CAP  220PF 50V 10% EMPTY  pkg 0402  page 303 : A = HSC_ON ; B = AGND_HSC

OSC1  Q_OSC4P  50MHZ OSC  pkg SMLF  page 155
  OE  = CLK_50M_EN
  GND  = GND
  \out\  = CLK_50M_RMII
  VDD  = P3V3_AUX

(kicad_pcb
	(version 20260206)
	(generator "pcbnew")
	(generator_version "10.0")
	(general
		(thickness 1.6)
		(legacy_teardrops no)
	)
	(paper "A4")
	(title_block
		(title "03242023_DA0F0TMBIJ0_F0T_Motherboard_J_brd_V01_OCP.brd")
		(comment 1 "Grand Teton / footprints 2517-2518 of 6105")
	)
	(layers
		(0 "F.Cu" signal "TOP")
		(4 "In1.Cu" signal "GND")
		(6 "In2.Cu" signal "IN1")
		(8 "In3.Cu" signal "GND1")
		(10 "In4.Cu" signal "IN2")
		(12 "In5.Cu" signal "GND2")
		(14 "In6.Cu" signal "IN3")
		(16 "In7.Cu" signal "GND3")
		(18 "In8.Cu" signal "VCC")
		(20 "In9.Cu" signal "VCC1")
		(22 "In10.Cu" signal "GND4")
		(24 "In11.Cu" signal "IN4")
		(26 "In12.Cu" signal "GND5")
		(28 "In13.Cu" signal "IN5")
		(30 "In14.Cu" signal "GND6")
		(32 "In15.Cu" signal "IN6")
		(34 "In16.Cu" signal "GND7")
		(2 "B.Cu" signal "BOTTOM")
		(9 "F.Adhes" user "F.Adhesive")
		(11 "B.Adhes" user "B.Adhesive")
		(13 "F.Paste" user "Package Geometry/Pastemask Top")
		(15 "B.Paste" user "Package Geometry/Pastemask Bottom")
		(5 "F.SilkS" user "Ref Des/Silkscreen Top")
		(7 "B.SilkS" user "Ref Des/Silkscreen Bottom")
		(1 "F.Mask" user "Board Geometry/Soldermask Top")
		(3 "B.Mask" user "Board Geometry/Soldermask Bottom")
		(17 "Dwgs.User" user "User.Drawings")
		(19 "Cmts.User" user "User.Comments")
		(21 "Eco1.User" user "User.Eco1")
		(23 "Eco2.User" user "User.Eco2")
		(25 "Edge.Cuts" user "Board Geometry/Outline")
		(27 "Margin" user)
		(31 "F.CrtYd" user "Package Geometry/Place Bound Top")
		(29 "B.CrtYd" user "Package Geometry/Place Bound Bottom")
		(35 "F.Fab" user "Ref Des/Assembly Top")
		(33 "B.Fab" user "Ref Des/Assembly Bottom")
	)
	(footprint ""
		(layer "F.Cu")
		(at 214.86241 -26.111454 90)
		(property "Reference" "OSC1"
			(at 1.289812 2.894076 0)
			(unlocked yes)
			(layer "F.SilkS")
			(effects
				(font
					(size 0.7874 0.5842)
					(thickness 0.1524)
				)
				(justify left)
			)
		)
		(property "Value" ""
			(at 0 0 90)
			(layer "F.Fab")
			(effects
				(font
					(size 1.27 1.27)
				)
			)
		)
		(duplicate_pad_numbers_are_jumpers no)
		(fp_line
			(start 1.546098 -1.94945)
			(end -1.546098 -1.94945)
			(stroke
				(width 0.1524)
				(type default)
			)
			(layer "F.SilkS")
		)
		(fp_line
			(start -1.546098 -1.94945)
			(end -1.546098 1.94945)
			(stroke
				(width 0.1524)
				(type default)
			)
			(layer "F.SilkS")
		)
		(fp_line
			(start 1.546098 1.94945)
			(end 1.546098 -1.94945)
			(stroke
				(width 0.1524)
				(type default)
			)
			(layer "F.SilkS")
		)
		(fp_line
			(start -1.546098 1.94945)
			(end 1.546098 1.94945)
			(stroke
				(width 0.1524)
				(type default)
			)
			(layer "F.SilkS")
		)
		(fp_poly
			(pts
				(xy -0.947674 -2.054098) (xy -1.430274 -3.374898) (xy -0.312674 -3.374898)
			)
			(stroke
				(width 0)
				(type default)
			)
			(fill yes)
			(layer "F.SilkS")
		)
		(fp_line
			(start 1.299972 -1.649984)
			(end 1.299972 1.649984)
			(stroke
				(width 0.1)
				(type default)
			)
			(layer "F.Fab")
		)
		(fp_line
			(start -1.299972 -1.649984)
			(end 1.299972 -1.649984)
			(stroke
				(width 0.1)
				(type default)
			)
			(layer "F.Fab")
		)
		(fp_line
			(start 1.299972 1.649984)
			(end -1.299972 1.649984)
			(stroke
				(width 0.1)
				(type default)
			)
			(layer "F.Fab")
		)
		(fp_line
			(start -1.299972 1.649984)
			(end -1.299972 -1.649984)
			(stroke
				(width 0.1)
				(type default)
			)
			(layer "F.Fab")
		)
		(fp_poly
			(pts
				(xy -1.768094 -1.059942) (xy -3.088894 -1.694942) (xy -3.088894 -0.577342)
			)
			(stroke
				(width 0)
				(type default)
			)
			(fill yes)
			(layer "F.Fab")
		)
		(pad "1" smd rect
			(at -0.8001 -1.059942 90)
			(size 1.2192 1.4986)
			(layers "F.Cu" "F.Mask" "F.Paste")
			(net "CLK_50M_EN")
		)
		(pad "2" smd rect
			(at -0.8001 1.059942 270)
			(size 1.2192 1.4986)
			(layers "F.Cu" "F.Mask" "F.Paste")
			(net "GND")
		)
		(pad "3" smd rect
			(at 0.8001 1.059942 90)
			(size 1.2192 1.4986)
			(layers "F.Cu" "F.Mask" "F.Paste")
			(net "CLK_50M_RMII")
		)
		(pad "4" smd rect
			(at 0.8001 -1.059942 90)
			(size 1.2192 1.4986)
			(layers "F.Cu" "F.Mask" "F.Paste")
			(net "P3V3_AUX")
		)
	)
	(footprint ""
		(layer "F.Cu")
		(at 237.401608 -402.689822)
		(property "Reference" "PC2225"
			(at 0 0 0)
			(layer "F.SilkS")
			(hide yes)
			(effects
				(font
					(size 1.27 1.27)
				)
			)
		)
		(property "Value" ""
			(at 0 0 0)
			(layer "F.Fab")
			(effects
				(font
					(size 1.27 1.27)
				)
			)
		)
		(duplicate_pad_numbers_are_jumpers no)
		(fp_line
			(start -0.7874 -0.4064)
			(end 0.7874 -0.4064)
			(stroke
				(width 0.1524)
				(type default)
			)
			(layer "F.SilkS")
		)
		(fp_line
			(start -0.7874 0.4064)
			(end -0.7874 -0.4064)
			(stroke
				(width 0.1524)
				(type default)
			)
			(layer "F.SilkS")
		)
		(fp_line
			(start 0.7874 -0.4064)
			(end 0.7874 0.4064)
			(stroke
				(width 0.1524)
				(type default)
			)
			(layer "F.SilkS")
		)
		(fp_line
			(start 0.7874 0.4064)
			(end -0.7874 0.4064)
			(stroke
				(width 0.1524)
				(type default)
			)
			(layer "F.SilkS")
		)
		(fp_line
			(start -0.67945 -0.305054)
			(end -0.12065 -0.305054)
			(stroke
				(width 0.1)
				(type default)
			)
			(layer "F.Fab")
		)
		(fp_line
			(start -0.67945 0.3048)
			(end -0.67945 -0.305054)
			(stroke
				(width 0.1)
				(type default)
			)
			(layer "F.Fab")
		)
		(fp_line
			(start -0.12065 -0.305054)
			(end -0.12065 -0.2794)
			(stroke
				(width 0.1)
				(type default)
			)
			(layer "F.Fab")
		)
		(fp_line
			(start -0.12065 -0.2794)
			(end 0.12065 -0.2794)
			(stroke
				(width 0.1)
				(type default)
			)
			(layer "F.Fab")
		)
		(fp_line
			(start -0.12065 0.2794)
			(end -0.12065 0.3048)
			(stroke
				(width 0.1)
				(type default)
			)
			(layer "F.Fab")
		)
		(fp_line
			(start -0.12065 0.3048)
			(end -0.67945 0.3048)
			(stroke
				(width 0.1)
				(type default)
			)
			(layer "F.Fab")
		)
		(fp_line
			(start 0.120396 0.2794)
			(end -0.12065 0.2794)
			(stroke
				(width 0.1)
				(type default)
			)
			(layer "F.Fab")
		)
		(fp_line
			(start 0.120396 0.3048)
			(end 0.120396 0.2794)
			(stroke
				(width 0.1)
				(type default)
			)
			(layer "F.Fab")
		)
		(fp_line
			(start 0.12065 -0.3048)
			(end 0.67945 -0.3048)
			(stroke
				(width 0.1)
				(type default)
			)
			(layer "F.Fab")
		)
		(fp_line
			(start 0.12065 -0.2794)
			(end 0.12065 -0.3048)
			(stroke
				(width 0.1)
				(type default)
			)
			(layer "F.Fab")
		)
		(fp_line
			(start 0.67945 -0.3048)
			(end 0.67945 0.3048)
			(stroke
				(width 0.1)
				(type default)
			)
			(layer "F.Fab")
		)
		(fp_line
			(start 0.67945 0.3048)
			(end 0.120396 0.3048)
			(stroke
				(width 0.1)
				(type default)
			)
			(layer "F.Fab")
		)
		(pad "1" smd circle
			(at -0.40005 0)
			(size 0 0)
			(layers "F.Cu" "F.Mask" "F.Paste")
			(net "HSC_ON")
		)
		(pad "2" smd circle
			(at 0.40005 0)
			(size 0 0)
			(layers "F.Cu" "F.Mask" "F.Paste")
			(net "AGND_HSC")
		)
	)
)
